FILE_TYPE=LIBRARY_PARTS;
TIME=' Created/Modified on Fri Feb 08 08:35:19 2002' ;
primitive 'Q_CAP','Q_CAP_0402LF';
  pin
    'A':
      PIN_NUMBER='(1)';
      PINUSE='UNSPEC';
      NO_LOAD_CHECK='BOTH';
      NO_IO_CHECK='BOTH';
      ALLOW_CONNECT='TRUE';
      PIN_GROUP='1';
    'B':
      PIN_NUMBER='(2)';
      PINUSE='UNSPEC';
      NO_LOAD_CHECK='BOTH';
      NO_IO_CHECK='BOTH';
      ALLOW_CONNECT='TRUE';
      PIN_GROUP='1';
  end_pin;
  body
    PART_NAME='Q_CAP';
    PHYS_DES_PREFIX='C';
  end_body;
end_primitive;
END.
